(kicad_pcb
	(version 20260206)
	(generator "pcbnew")
	(generator_version "10.0")
	(general
		(thickness 1.6)
		(legacy_teardrops no)
	)
	(paper "A4")
	(title_block
		(title "12092022_DA0F0TMDCD0_F0T_Management_Board_D_brd_V3_OCP.brd")
		(comment 1 "Grand Teton / footprints 1332-1338 of 1440")
	)
	(layers
		(0 "F.Cu" signal "TOP")
		(4 "In1.Cu" signal "GND")
		(6 "In2.Cu" signal "IN1")
		(8 "In3.Cu" signal "GND1")
		(10 "In4.Cu" signal "IN2")
		(12 "In5.Cu" signal "VCC")
		(14 "In6.Cu" signal "VCC1")
		(16 "In7.Cu" signal "IN3")
		(18 "In8.Cu" signal "GND2")
		(20 "In9.Cu" signal "IN4")
		(22 "In10.Cu" signal "GND3")
		(2 "B.Cu" signal "BOTTOM")
		(9 "F.Adhes" user "F.Adhesive")
		(11 "B.Adhes" user "B.Adhesive")
		(13 "F.Paste" user "Package Geometry/Pastemask Top")
		(15 "B.Paste" user "Package Geometry/Pastemask Bottom")
		(5 "F.SilkS" user "Ref Des/Silkscreen Top")
		(7 "B.SilkS" user "Ref Des/Silkscreen Bottom")
		(1 "F.Mask" user "Board Geometry/Soldermask Top")
		(3 "B.Mask" user "Board Geometry/Soldermask Bottom")
		(17 "Dwgs.User" user "User.Drawings")
		(19 "Cmts.User" user "User.Comments")
		(21 "Eco1.User" user "User.Eco1")
		(23 "Eco2.User" user "User.Eco2")
		(25 "Edge.Cuts" user "Board Geometry/Outline")
		(27 "Margin" user)
		(31 "F.CrtYd" user "Package Geometry/Place Bound Top")
		(29 "B.CrtYd" user "Package Geometry/Place Bound Bottom")
		(35 "F.Fab" user "Ref Des/Assembly Top")
		(33 "B.Fab" user "Ref Des/Assembly Bottom")
	)
	(footprint ""
		(layer "B.Cu")
		(at 36.068 -106.3625 -90)
		(property "Reference" "R224"
			(at 0 0 90)
			(layer "B.SilkS")
			(hide yes)
			(effects
				(font
					(size 1.27 1.27)
				)
				(justify mirror)
			)
		)
		(property "Value" ""
			(at 0 0 90)
			(layer "B.Fab")
			(effects
				(font
					(size 1.27 1.27)
				)
				(justify mirror)
			)
		)
		(duplicate_pad_numbers_are_jumpers no)
		(fp_line
			(start -0.7874 0.4064)
			(end 0.7874 0.4064)
			(stroke
				(width 0.1524)
				(type default)
			)
			(layer "B.SilkS")
		)
		(fp_line
			(start 0.7874 0.4064)
			(end 0.7874 -0.4064)
			(stroke
				(width 0.1524)
				(type default)
			)
			(layer "B.SilkS")
		)
		(fp_line
			(start -0.7874 -0.4064)
			(end -0.7874 0.4064)
			(stroke
				(width 0.1524)
				(type default)
			)
			(layer "B.SilkS")
		)
		(fp_line
			(start 0.7874 -0.4064)
			(end -0.7874 -0.4064)
			(stroke
				(width 0.1524)
				(type default)
			)
			(layer "B.SilkS")
		)
		(fp_line
			(start -0.67945 0.3048)
			(end -0.120396 0.3048)
			(stroke
				(width 0.1)
				(type default)
			)
			(layer "B.Fab")
		)
		(fp_line
			(start -0.120396 0.3048)
			(end -0.120396 0.2794)
			(stroke
				(width 0.1)
				(type default)
			)
			(layer "B.Fab")
		)
		(fp_line
			(start 0.12065 0.3048)
			(end 0.67945 0.3048)
			(stroke
				(width 0.1)
				(type default)
			)
			(layer "B.Fab")
		)
		(fp_line
			(start 0.67945 0.3048)
			(end 0.67945 -0.305054)
			(stroke
				(width 0.1)
				(type default)
			)
			(layer "B.Fab")
		)
		(fp_line
			(start -0.120396 0.2794)
			(end 0.12065 0.2794)
			(stroke
				(width 0.1)
				(type default)
			)
			(layer "B.Fab")
		)
		(fp_line
			(start 0.12065 0.2794)
			(end 0.12065 0.3048)
			(stroke
				(width 0.1)
				(type default)
			)
			(layer "B.Fab")
		)
		(fp_line
			(start -0.12065 -0.2794)
			(end -0.12065 -0.3048)
			(stroke
				(width 0.1)
				(type default)
			)
			(layer "B.Fab")
		)
		(fp_line
			(start 0.12065 -0.2794)
			(end -0.12065 -0.2794)
			(stroke
				(width 0.1)
				(type default)
			)
			(layer "B.Fab")
		)
		(fp_line
			(start -0.67945 -0.3048)
			(end -0.67945 0.3048)
			(stroke
				(width 0.1)
				(type default)
			)
			(layer "B.Fab")
		)
		(fp_line
			(start -0.12065 -0.3048)
			(end -0.67945 -0.3048)
			(stroke
				(width 0.1)
				(type default)
			)
			(layer "B.Fab")
		)
		(fp_line
			(start 0.12065 -0.305054)
			(end 0.12065 -0.2794)
			(stroke
				(width 0.1)
				(type default)
			)
			(layer "B.Fab")
		)
		(fp_line
			(start 0.67945 -0.305054)
			(end 0.12065 -0.305054)
			(stroke
				(width 0.1)
				(type default)
			)
			(layer "B.Fab")
		)
		(pad "1" smd circle
			(at 0.40005 0 90)
			(size 0 0)
			(layers "B.Cu" "B.Mask" "B.Paste")
			(net "JTAG_1_BMC_TDO_R")
		)
		(pad "2" smd circle
			(at -0.40005 0 90)
			(size 0 0)
			(layers "B.Cu" "B.Mask" "B.Paste")
			(net "JTAG_MB_TDO")
		)
	)
	(footprint ""
		(layer "B.Cu")
		(at 75.438 -24.7904 180)
		(property "Reference" "R696"
			(at 0 0 0)
			(layer "B.SilkS")
			(hide yes)
			(effects
				(font
					(size 1.27 1.27)
				)
				(justify mirror)
			)
		)
		(property "Value" ""
			(at 0 0 0)
			(layer "B.Fab")
			(effects
				(font
					(size 1.27 1.27)
				)
				(justify mirror)
			)
		)
		(duplicate_pad_numbers_are_jumpers no)
		(fp_line
			(start 0.7874 0.4064)
			(end 0.7874 -0.4064)
			(stroke
				(width 0.1524)
				(type default)
			)
			(layer "B.SilkS")
		)
		(fp_line
			(start 0.7874 -0.4064)
			(end -0.7874 -0.4064)
			(stroke
				(width 0.1524)
				(type default)
			)
			(layer "B.SilkS")
		)
		(fp_line
			(start -0.7874 0.4064)
			(end 0.7874 0.4064)
			(stroke
				(width 0.1524)
				(type default)
			)
			(layer "B.SilkS")
		)
		(fp_line
			(start -0.7874 -0.4064)
			(end -0.7874 0.4064)
			(stroke
				(width 0.1524)
				(type default)
			)
			(layer "B.SilkS")
		)
		(fp_line
			(start 0.67945 0.3048)
			(end 0.67945 -0.305054)
			(stroke
				(width 0.1)
				(type default)
			)
			(layer "B.Fab")
		)
		(fp_line
			(start 0.67945 -0.305054)
			(end 0.12065 -0.305054)
			(stroke
				(width 0.1)
				(type default)
			)
			(layer "B.Fab")
		)
		(fp_line
			(start 0.12065 0.3048)
			(end 0.67945 0.3048)
			(stroke
				(width 0.1)
				(type default)
			)
			(layer "B.Fab")
		)
		(fp_line
			(start 0.12065 0.2794)
			(end 0.12065 0.3048)
			(stroke
				(width 0.1)
				(type default)
			)
			(layer "B.Fab")
		)
		(fp_line
			(start 0.12065 -0.2794)
			(end -0.12065 -0.2794)
			(stroke
				(width 0.1)
				(type default)
			)
			(layer "B.Fab")
		)
		(fp_line
			(start 0.12065 -0.305054)
			(end 0.12065 -0.2794)
			(stroke
				(width 0.1)
				(type default)
			)
			(layer "B.Fab")
		)
		(fp_line
			(start -0.120396 0.3048)
			(end -0.120396 0.2794)
			(stroke
				(width 0.1)
				(type default)
			)
			(layer "B.Fab")
		)
		(fp_line
			(start -0.120396 0.2794)
			(end 0.12065 0.2794)
			(stroke
				(width 0.1)
				(type default)
			)
			(layer "B.Fab")
		)
		(fp_line
			(start -0.12065 -0.2794)
			(end -0.12065 -0.3048)
			(stroke
				(width 0.1)
				(type default)
			)
			(layer "B.Fab")
		)
		(fp_line
			(start -0.12065 -0.3048)
			(end -0.67945 -0.3048)
			(stroke
				(width 0.1)
				(type default)
			)
			(layer "B.Fab")
		)
		(fp_line
			(start -0.67945 0.3048)
			(end -0.120396 0.3048)
			(stroke
				(width 0.1)
				(type default)
			)
			(layer "B.Fab")
		)
		(fp_line
			(start -0.67945 -0.3048)
			(end -0.67945 0.3048)
			(stroke
				(width 0.1)
				(type default)
			)
			(layer "B.Fab")
		)
		(pad "1" smd circle
			(at 0.40005 0)
			(size 0 0)
			(layers "B.Cu" "B.Mask" "B.Paste")
			(net "LED_POSTCODE_3")
		)
		(pad "2" smd circle
			(at -0.40005 0)
			(size 0 0)
			(layers "B.Cu" "B.Mask" "B.Paste")
			(net "LED_POSTCODE_3_R1")
		)
	)
	(footprint ""
		(layer "B.Cu")
		(at 11.557 -43.688)
		(property "Reference" "ME2"
			(at 0 0 0)
			(layer "B.SilkS")
			(hide yes)
			(effects
				(font
					(size 1.27 1.27)
				)
				(justify mirror)
			)
		)
		(property "Value" ""
			(at 0 0 0)
			(layer "B.Fab")
			(effects
				(font
					(size 1.27 1.27)
				)
				(justify mirror)
			)
		)
		(duplicate_pad_numbers_are_jumpers no)
		(fp_poly
			(pts
				(xy -1.32715 -3.4417) (xy -2.01295 -3.4417) (xy -2.01295 -3.2512) (xy -1.32715 -3.2512)
			)
			(stroke
				(width 0)
				(type default)
			)
			(fill yes)
			(layer "B.SilkS")
		)
		(fp_poly
			(pts
				(xy 0 -0.5842) (xy -3.3401 -0.5842) (xy -3.3401 0) (xy 0 0)
			)
			(stroke
				(width 0)
				(type default)
			)
			(fill yes)
			(layer "B.SilkS")
		)
		(fp_poly
			(pts
				(xy 0.070612 -0.681228) (xy 0.197612 -0.820928) (xy -0.852678 -1.91262) (xy -0.728472 -3.29184)
				(xy 0.248412 -4.300728) (xy 0.184912 -4.478528) (xy 0.007112 -4.503928) (xy -0.684022 -3.785616)
				(xy -0.65659 -4.0894) (xy -0.97155 -4.3434) (xy -1.22555 -4.3561) (xy -1.46685 -4.4704) (xy -2.01295 -4.4704)
				(xy -2.15265 -4.4069) (xy -2.44475 -4.191) (xy -2.49555 -4.191) (xy -2.59715 -4.2926) (xy -2.80035 -4.2672)
				(xy -2.88925 -4.1656) (xy -2.88925 -4.029456) (xy -3.345688 -4.503928) (xy -3.523488 -4.478528)
				(xy -3.586988 -4.300728) (xy -2.88925 -3.58013) (xy -2.88925 -3.3147) (xy -2.82575 -3.2385) (xy -2.67335 -3.2385)
				(xy -2.521966 -1.875282) (xy -2.545842 -1.85039)
				(arc
					(start -2.55905 -1.8415)
					(mid -2.648099 -1.766068)
					(end -2.717292 -1.672082)
				)
				(xy -3.536188 -0.820928) (xy -3.409188 -0.681228) (xy -3.244088 -0.693928)
				(arc
					(start -2.737612 -1.216914)
					(mid -2.31728 -0.925553)
					(end -1.86055 -1.1557)
				)
				(xy -0.92075 -1.1557) (xy -0.888492 -1.51384) (xy -0.094488 -0.693928)
			)
			(stroke
				(width 0)
				(type default)
			)
			(fill yes)
			(layer "B.SilkS")
		)
	)
	(footprint ""
		(layer "B.Cu")
		(at 56.331358 -46.200568)
		(property "Reference" "C85"
			(at 0 0 0)
			(layer "B.SilkS")
			(hide yes)
			(effects
				(font
					(size 1.27 1.27)
				)
				(justify mirror)
			)
		)
		(property "Value" ""
			(at 0 0 0)
			(layer "B.Fab")
			(effects
				(font
					(size 1.27 1.27)
				)
				(justify mirror)
			)
		)
		(duplicate_pad_numbers_are_jumpers no)
		(fp_line
			(start -0.7874 -0.4064)
			(end -0.7874 0.4064)
			(stroke
				(width 0.1524)
				(type default)
			)
			(layer "B.SilkS")
		)
		(fp_line
			(start -0.7874 0.4064)
			(end 0.7874 0.4064)
			(stroke
				(width 0.1524)
				(type default)
			)
			(layer "B.SilkS")
		)
		(fp_line
			(start 0.7874 -0.4064)
			(end -0.7874 -0.4064)
			(stroke
				(width 0.1524)
				(type default)
			)
			(layer "B.SilkS")
		)
		(fp_line
			(start 0.7874 0.4064)
			(end 0.7874 -0.4064)
			(stroke
				(width 0.1524)
				(type default)
			)
			(layer "B.SilkS")
		)
		(fp_line
			(start -0.67945 -0.3048)
			(end -0.67945 0.3048)
			(stroke
				(width 0.1)
				(type default)
			)
			(layer "B.Fab")
		)
		(fp_line
			(start -0.67945 0.3048)
			(end -0.120396 0.3048)
			(stroke
				(width 0.1)
				(type default)
			)
			(layer "B.Fab")
		)
		(fp_line
			(start -0.12065 -0.3048)
			(end -0.67945 -0.3048)
			(stroke
				(width 0.1)
				(type default)
			)
			(layer "B.Fab")
		)
		(fp_line
			(start -0.12065 -0.2794)
			(end -0.12065 -0.3048)
			(stroke
				(width 0.1)
				(type default)
			)
			(layer "B.Fab")
		)
		(fp_line
			(start -0.120396 0.2794)
			(end 0.12065 0.2794)
			(stroke
				(width 0.1)
				(type default)
			)
			(layer "B.Fab")
		)
		(fp_line
			(start -0.120396 0.3048)
			(end -0.120396 0.2794)
			(stroke
				(width 0.1)
				(type default)
			)
			(layer "B.Fab")
		)
		(fp_line
			(start 0.12065 -0.305054)
			(end 0.12065 -0.2794)
			(stroke
				(width 0.1)
				(type default)
			)
			(layer "B.Fab")
		)
		(fp_line
			(start 0.12065 -0.2794)
			(end -0.12065 -0.2794)
			(stroke
				(width 0.1)
				(type default)
			)
			(layer "B.Fab")
		)
		(fp_line
			(start 0.12065 0.2794)
			(end 0.12065 0.3048)
			(stroke
				(width 0.1)
				(type default)
			)
			(layer "B.Fab")
		)
		(fp_line
			(start 0.12065 0.3048)
			(end 0.67945 0.3048)
			(stroke
				(width 0.1)
				(type default)
			)
			(layer "B.Fab")
		)
		(fp_line
			(start 0.67945 -0.305054)
			(end 0.12065 -0.305054)
			(stroke
				(width 0.1)
				(type default)
			)
			(layer "B.Fab")
		)
		(fp_line
			(start 0.67945 0.3048)
			(end 0.67945 -0.305054)
			(stroke
				(width 0.1)
				(type default)
			)
			(layer "B.Fab")
		)
		(pad "1" smd circle
			(at 0.40005 0 180)
			(size 0 0)
			(layers "B.Cu" "B.Mask" "B.Paste")
			(net "P3V3_RGM")
		)
		(pad "2" smd circle
			(at -0.40005 0 180)
			(size 0 0)
			(layers "B.Cu" "B.Mask" "B.Paste")
			(net "GND")
		)
	)
	(footprint ""
		(layer "B.Cu")
		(at 44.0944 -62.0014 -90)
		(property "Reference" "R22"
			(at 0 0 90)
			(layer "B.SilkS")
			(hide yes)
			(effects
				(font
					(size 1.27 1.27)
				)
				(justify mirror)
			)
		)
		(property "Value" ""
			(at 0 0 90)
			(layer "B.Fab")
			(effects
				(font
					(size 1.27 1.27)
				)
				(justify mirror)
			)
		)
		(duplicate_pad_numbers_are_jumpers no)
		(fp_line
			(start -0.7874 0.4064)
			(end 0.7874 0.4064)
			(stroke
				(width 0.1524)
				(type default)
			)
			(layer "B.SilkS")
		)
		(fp_line
			(start 0.7874 0.4064)
			(end 0.7874 -0.4064)
			(stroke
				(width 0.1524)
				(type default)
			)
			(layer "B.SilkS")
		)
		(fp_line
			(start -0.7874 -0.4064)
			(end -0.7874 0.4064)
			(stroke
				(width 0.1524)
				(type default)
			)
			(layer "B.SilkS")
		)
		(fp_line
			(start 0.7874 -0.4064)
			(end -0.7874 -0.4064)
			(stroke
				(width 0.1524)
				(type default)
			)
			(layer "B.SilkS")
		)
		(fp_line
			(start -0.67945 0.3048)
			(end -0.120396 0.3048)
			(stroke
				(width 0.1)
				(type default)
			)
			(layer "B.Fab")
		)
		(fp_line
			(start -0.120396 0.3048)
			(end -0.120396 0.2794)
			(stroke
				(width 0.1)
				(type default)
			)
			(layer "B.Fab")
		)
		(fp_line
			(start 0.12065 0.3048)
			(end 0.67945 0.3048)
			(stroke
				(width 0.1)
				(type default)
			)
			(layer "B.Fab")
		)
		(fp_line
			(start 0.67945 0.3048)
			(end 0.67945 -0.305054)
			(stroke
				(width 0.1)
				(type default)
			)
			(layer "B.Fab")
		)
		(fp_line
			(start -0.120396 0.2794)
			(end 0.12065 0.2794)
			(stroke
				(width 0.1)
				(type default)
			)
			(layer "B.Fab")
		)
		(fp_line
			(start 0.12065 0.2794)
			(end 0.12065 0.3048)
			(stroke
				(width 0.1)
				(type default)
			)
			(layer "B.Fab")
		)
		(fp_line
			(start -0.12065 -0.2794)
			(end -0.12065 -0.3048)
			(stroke
				(width 0.1)
				(type default)
			)
			(layer "B.Fab")
		)
		(fp_line
			(start 0.12065 -0.2794)
			(end -0.12065 -0.2794)
			(stroke
				(width 0.1)
				(type default)
			)
			(layer "B.Fab")
		)
		(fp_line
			(start -0.67945 -0.3048)
			(end -0.67945 0.3048)
			(stroke
				(width 0.1)
				(type default)
			)
			(layer "B.Fab")
		)
		(fp_line
			(start -0.12065 -0.3048)
			(end -0.67945 -0.3048)
			(stroke
				(width 0.1)
				(type default)
			)
			(layer "B.Fab")
		)
		(fp_line
			(start 0.12065 -0.305054)
			(end 0.12065 -0.2794)
			(stroke
				(width 0.1)
				(type default)
			)
			(layer "B.Fab")
		)
		(fp_line
			(start 0.67945 -0.305054)
			(end 0.12065 -0.305054)
			(stroke
				(width 0.1)
				(type default)
			)
			(layer "B.Fab")
		)
		(pad "1" smd circle
			(at 0.40005 0 90)
			(size 0 0)
			(layers "B.Cu" "B.Mask" "B.Paste")
			(net "V_DACB_R")
		)
		(pad "2" smd circle
			(at -0.40005 0 90)
			(size 0 0)
			(layers "B.Cu" "B.Mask" "B.Paste")
			(net "GND")
		)
	)
	(footprint ""
		(layer "B.Cu")
		(at 7.838186 -3.639312)
		(property "Reference" ""
			(at 0 0 0)
			(layer "B.SilkS")
			(hide yes)
			(effects
				(font
					(size 1.27 1.27)
				)
				(justify mirror)
			)
		)
		(property "Value" ""
			(at 0 0 0)
			(layer "B.Fab")
			(effects
				(font
					(size 1.27 1.27)
				)
				(justify mirror)
			)
		)
		(duplicate_pad_numbers_are_jumpers no)
		(pad "1" smd circle
			(at 0 0 180)
			(size 0.9906 0.9906)
			(layers "B.Cu" "B.Mask" "B.Paste")
			(net "Net_135")
		)
		(zone
			(layer "B.Cu")
			(hatch none 0.5)
			(connect_pads
				(clearance 0)
			)
			(min_thickness 0.25)
			(keepout
				(tracks not_allowed)
				(vias allowed)
				(pads allowed)
				(copperpour not_allowed)
				(footprints allowed)
			)
			(placement
				(enabled no)
				(sheetname "")
			)
			(fill
				(thermal_gap 0.5)
				(thermal_bridge_width 0.5)
				(island_removal_mode 0)
			)
			(polygon
				(pts
					(arc
						(start 9.463786 -3.639312)
						(mid 6.212586 -3.639312)
						(end 9.463786 -3.639312)
					)
				)
			)
		)
	)
	(footprint ""
		(layer "B.Cu")
		(at 47.85487 -72.954134 180)
		(property "Reference" "C275"
			(at 0 0 0)
			(layer "B.SilkS")
			(hide yes)
			(effects
				(font
					(size 1.27 1.27)
				)
				(justify mirror)
			)
		)
		(property "Value" ""
			(at 0 0 0)
			(layer "B.Fab")
			(effects
				(font
					(size 1.27 1.27)
				)
				(justify mirror)
			)
		)
		(duplicate_pad_numbers_are_jumpers no)
		(fp_line
			(start 0.7874 0.4064)
			(end 0.7874 -0.4064)
			(stroke
				(width 0.1524)
				(type default)
			)
			(layer "B.SilkS")
		)
		(fp_line
			(start 0.7874 -0.4064)
			(end -0.7874 -0.4064)
			(stroke
				(width 0.1524)
				(type default)
			)
			(layer "B.SilkS")
		)
		(fp_line
			(start -0.7874 0.4064)
			(end 0.7874 0.4064)
			(stroke
				(width 0.1524)
				(type default)
			)
			(layer "B.SilkS")
		)
		(fp_line
			(start -0.7874 -0.4064)
			(end -0.7874 0.4064)
			(stroke
				(width 0.1524)
				(type default)
			)
			(layer "B.SilkS")
		)
		(fp_line
			(start 0.67945 0.3048)
			(end 0.67945 -0.305054)
			(stroke
				(width 0.1)
				(type default)
			)
			(layer "B.Fab")
		)
		(fp_line
			(start 0.67945 -0.305054)
			(end 0.12065 -0.305054)
			(stroke
				(width 0.1)
				(type default)
			)
			(layer "B.Fab")
		)
		(fp_line
			(start 0.12065 0.3048)
			(end 0.67945 0.3048)
			(stroke
				(width 0.1)
				(type default)
			)
			(layer "B.Fab")
		)
		(fp_line
			(start 0.12065 0.2794)
			(end 0.12065 0.3048)
			(stroke
				(width 0.1)
				(type default)
			)
			(layer "B.Fab")
		)
		(fp_line
			(start 0.12065 -0.2794)
			(end -0.12065 -0.2794)
			(stroke
				(width 0.1)
				(type default)
			)
			(layer "B.Fab")
		)
		(fp_line
			(start 0.12065 -0.305054)
			(end 0.12065 -0.2794)
			(stroke
				(width 0.1)
				(type default)
			)
			(layer "B.Fab")
		)
		(fp_line
			(start -0.120396 0.3048)
			(end -0.120396 0.2794)
			(stroke
				(width 0.1)
				(type default)
			)
			(layer "B.Fab")
		)
		(fp_line
			(start -0.120396 0.2794)
			(end 0.12065 0.2794)
			(stroke
				(width 0.1)
				(type default)
			)
			(layer "B.Fab")
		)
		(fp_line
			(start -0.12065 -0.2794)
			(end -0.12065 -0.3048)
			(stroke
				(width 0.1)
				(type default)
			)
			(layer "B.Fab")
		)
		(fp_line
			(start -0.12065 -0.3048)
			(end -0.67945 -0.3048)
			(stroke
				(width 0.1)
				(type default)
			)
			(layer "B.Fab")
		)
		(fp_line
			(start -0.67945 0.3048)
			(end -0.120396 0.3048)
			(stroke
				(width 0.1)
				(type default)
			)
			(layer "B.Fab")
		)
		(fp_line
			(start -0.67945 -0.3048)
			(end -0.67945 0.3048)
			(stroke
				(width 0.1)
				(type default)
			)
			(layer "B.Fab")
		)
		(pad "1" smd circle
			(at 0.40005 0)
			(size 0 0)
			(layers "B.Cu" "B.Mask" "B.Paste")
			(net "P3V_BAT_SENSOR")
		)
		(pad "2" smd circle
			(at -0.40005 0)
			(size 0 0)
			(layers "B.Cu" "B.Mask" "B.Paste")
			(net "GND")
		)
	)
)
